# BASEBOARD_FAB2 (Tioga Pass) — schematic netlist excerpt (pin names and nets, part order shuffled) for the footprints in the layout excerpt that follows; sources: Cadence DE-HDL packaged netlist, KiCad conversion of Wiwynn_Tioga_Pass_MB.brd

R25W103  RES  4.75K 1% EMPTY  pkg 0402  page 150 : A = P3V3_STBY ; B = BMC_STRAP_BIT20
R8E10  RES  33.2 1% CHIP  pkg 0402  page 184 : A = SPI_PCH_MOSI ; B = SPI_PCH_TPM_MOSI_R
C7A8  CAP  0.22UF 16V 10% X7R  pkg 0402  page 236 : A = P5V_STBY ; B = GND

(kicad_pcb
	(version 20260206)
	(generator "pcbnew")
	(generator_version "10.0")
	(general
		(thickness 1.6)
		(legacy_teardrops no)
	)
	(paper "A4")
	(title_block
		(title "Wiwynn_Tioga_Pass_MB.brd")
		(comment 1 "Tioga Pass / footprints 2088-2090 of 4770")
	)
	(layers
		(0 "F.Cu" signal "TOP")
		(4 "In1.Cu" signal "L2GND")
		(6 "In2.Cu" signal "L3")
		(8 "In3.Cu" signal "L4GND")
		(10 "In4.Cu" signal "L5")
		(12 "In5.Cu" signal "L6GND")
		(14 "In6.Cu" signal "L7VCC")
		(16 "In7.Cu" signal "L8VCC")
		(18 "In8.Cu" signal "L9GND")
		(20 "In9.Cu" signal "L10")
		(22 "In10.Cu" signal "L11GND")
		(24 "In11.Cu" signal "L12")
		(26 "In12.Cu" signal "L13GND")
		(2 "B.Cu" signal "BOTTOM")
		(9 "F.Adhes" user "F.Adhesive")
		(11 "B.Adhes" user "B.Adhesive")
		(13 "F.Paste" user "Package Geometry/Pastemask Top")
		(15 "B.Paste" user "Package Geometry/Pastemask Bottom")
		(5 "F.SilkS" user "Ref Des/Silkscreen Top")
		(7 "B.SilkS" user "Ref Des/Silkscreen Bottom")
		(1 "F.Mask" user "Board Geometry/Soldermask Top")
		(3 "B.Mask" user "Board Geometry/Soldermask Bottom")
		(17 "Dwgs.User" user "User.Drawings")
		(19 "Cmts.User" user "User.Comments")
		(21 "Eco1.User" user "User.Eco1")
		(23 "Eco2.User" user "User.Eco2")
		(25 "Edge.Cuts" user "Board Geometry/Outline")
		(27 "Margin" user)
		(31 "F.CrtYd" user "Package Geometry/Place Bound Top")
		(29 "B.CrtYd" user "Package Geometry/Place Bound Bottom")
		(35 "F.Fab" user "Ref Des/Assembly Top")
		(33 "B.Fab" user "Ref Des/Assembly Bottom")
	)
	(footprint ""
		(layer "F.Cu")
		(at 421.627046 -48.968152)
		(property "Reference" "R25W103"
			(at -0.8382 -0.67818 0)
			(unlocked yes)
			(layer "F.SilkS")
			(effects
				(font
					(size 0.4064 0.254)
					(thickness 0.1524)
				)
				(justify left)
			)
		)
		(property "Value" ""
			(at 0 0 0)
			(layer "F.Fab")
			(effects
				(font
					(size 1.27 1.27)
				)
			)
		)
		(duplicate_pad_numbers_are_jumpers no)
		(fp_poly
			(pts
				(xy -0.2794 -0.1016) (xy 0.2794 -0.1016) (xy 0.2794 0.9906) (xy -0.2794 0.9906)
			)
			(stroke
				(width 0)
				(type default)
			)
			(fill no)
			(layer "F.CrtYd")
		)
		(fp_line
			(start -0.2794 -0.1016)
			(end -0.2794 0.9906)
			(stroke
				(width 0.1)
				(type default)
			)
			(layer "F.Fab")
		)
		(fp_line
			(start -0.2794 0.9906)
			(end 0.2794 0.9906)
			(stroke
				(width 0.1)
				(type default)
			)
			(layer "F.Fab")
		)
		(fp_line
			(start 0.2794 -0.1016)
			(end -0.2794 -0.1016)
			(stroke
				(width 0.1)
				(type default)
			)
			(layer "F.Fab")
		)
		(fp_line
			(start 0.2794 0.9906)
			(end 0.2794 -0.1016)
			(stroke
				(width 0.1)
				(type default)
			)
			(layer "F.Fab")
		)
		(pad "1" smd rect
			(at 0 0)
			(size 0.508 0.508)
			(layers "F.Cu" "F.Mask" "F.Paste")
			(net "P3V3_STBY")
		)
		(pad "2" smd rect
			(at 0 0.889)
			(size 0.508 0.508)
			(layers "F.Cu" "F.Mask" "F.Paste")
			(net "BMC_STRAP_BIT20")
		)
		(zone
			(layer "F.Cu")
			(hatch none 0.5)
			(connect_pads
				(clearance 0)
			)
			(min_thickness 0.25)
			(keepout
				(tracks allowed)
				(vias not_allowed)
				(pads allowed)
				(copperpour not_allowed)
				(footprints allowed)
			)
			(placement
				(enabled no)
				(sheetname "")
			)
			(fill
				(thermal_gap 0.5)
				(thermal_bridge_width 0.5)
				(island_removal_mode 0)
			)
			(polygon
				(pts
					(xy 421.373046 -48.714152) (xy 421.881046 -48.714152) (xy 421.881046 -48.333152) (xy 421.373046 -48.333152)
				)
			)
		)
		(zone
			(layer "F.Cu")
			(hatch none 0.5)
			(connect_pads
				(clearance 0)
			)
			(min_thickness 0.25)
			(keepout
				(tracks not_allowed)
				(vias allowed)
				(pads allowed)
				(copperpour not_allowed)
				(footprints allowed)
			)
			(placement
				(enabled no)
				(sheetname "")
			)
			(fill
				(thermal_gap 0.5)
				(thermal_bridge_width 0.5)
				(island_removal_mode 0)
			)
			(polygon
				(pts
					(xy 421.373046 -48.333152) (xy 421.881046 -48.333152) (xy 421.881046 -48.714152) (xy 421.373046 -48.714152)
				)
			)
		)
	)
	(footprint ""
		(layer "F.Cu")
		(at 372.491 -154.4955)
		(property "Reference" "C7A8"
			(at 0 0 0)
			(layer "F.SilkS")
			(hide yes)
			(effects
				(font
					(size 1.27 1.27)
				)
			)
		)
		(property "Value" ""
			(at 0 0 0)
			(layer "F.Fab")
			(effects
				(font
					(size 1.27 1.27)
				)
			)
		)
		(duplicate_pad_numbers_are_jumpers no)
		(fp_poly
			(pts
				(xy 0.3048 -0.1016) (xy 0.3048 0.9906) (xy -0.3048 0.9906) (xy -0.3048 -0.1016)
			)
			(stroke
				(width 0)
				(type default)
			)
			(fill no)
			(layer "F.CrtYd")
		)
		(fp_line
			(start -0.3048 -0.1016)
			(end -0.3048 0.9906)
			(stroke
				(width 0.1)
				(type default)
			)
			(layer "F.Fab")
		)
		(fp_line
			(start -0.3048 0.9906)
			(end 0.3048 0.9906)
			(stroke
				(width 0.1)
				(type default)
			)
			(layer "F.Fab")
		)
		(fp_line
			(start 0.3048 -0.1016)
			(end -0.3048 -0.1016)
			(stroke
				(width 0.1)
				(type default)
			)
			(layer "F.Fab")
		)
		(fp_line
			(start 0.3048 0.9906)
			(end 0.3048 -0.1016)
			(stroke
				(width 0.1)
				(type default)
			)
			(layer "F.Fab")
		)
		(pad "1" smd rect
			(at 0 0)
			(size 0.508 0.508)
			(layers "F.Cu" "F.Mask" "F.Paste")
			(net "P5V_STBY")
		)
		(pad "2" smd rect
			(at 0 0.889)
			(size 0.508 0.508)
			(layers "F.Cu" "F.Mask" "F.Paste")
			(net "GND")
		)
		(zone
			(layer "F.Cu")
			(hatch none 0.5)
			(connect_pads
				(clearance 0)
			)
			(min_thickness 0.25)
			(keepout
				(tracks allowed)
				(vias not_allowed)
				(pads allowed)
				(copperpour not_allowed)
				(footprints allowed)
			)
			(placement
				(enabled no)
				(sheetname "")
			)
			(fill
				(thermal_gap 0.5)
				(thermal_bridge_width 0.5)
				(island_removal_mode 0)
			)
			(polygon
				(pts
					(xy 372.237 -154.2415) (xy 372.745 -154.2415) (xy 372.745 -153.8605) (xy 372.237 -153.8605)
				)
			)
		)
		(zone
			(layer "F.Cu")
			(hatch none 0.5)
			(connect_pads
				(clearance 0)
			)
			(min_thickness 0.25)
			(keepout
				(tracks not_allowed)
				(vias allowed)
				(pads allowed)
				(copperpour not_allowed)
				(footprints allowed)
			)
			(placement
				(enabled no)
				(sheetname "")
			)
			(fill
				(thermal_gap 0.5)
				(thermal_bridge_width 0.5)
				(island_removal_mode 0)
			)
			(polygon
				(pts
					(xy 372.237 -153.8605) (xy 372.745 -153.8605) (xy 372.745 -154.2415) (xy 372.237 -154.2415)
				)
			)
		)
	)
	(footprint ""
		(layer "F.Cu")
		(at 406.9461 -64.897 90)
		(property "Reference" "R8E10"
			(at 0 0 90)
			(layer "F.SilkS")
			(hide yes)
			(effects
				(font
					(size 1.27 1.27)
				)
			)
		)
		(property "Value" ""
			(at 0 0 90)
			(layer "F.Fab")
			(effects
				(font
					(size 1.27 1.27)
				)
			)
		)
		(duplicate_pad_numbers_are_jumpers no)
		(fp_poly
			(pts
				(xy -0.2794 -0.1016) (xy 0.2794 -0.1016) (xy 0.2794 0.9906) (xy -0.2794 0.9906)
			)
			(stroke
				(width 0)
				(type default)
			)
			(fill no)
			(layer "F.CrtYd")
		)
		(pad "1" smd rect
			(at 0 0 90)
			(size 0.508 0.508)
			(layers "F.Cu" "F.Mask" "F.Paste")
			(net "SPI_PCH_MOSI")
		)
		(pad "2" smd rect
			(at 0 0.889 90)
			(size 0.508 0.508)
			(layers "F.Cu" "F.Mask" "F.Paste")
			(net "SPI_PCH_TPM_MOSI_R")
		)
		(zone
			(layer "F.Cu")
			(hatch none 0.5)
			(connect_pads
				(clearance 0)
			)
			(min_thickness 0.25)
			(keepout
				(tracks allowed)
				(vias not_allowed)
				(pads allowed)
				(copperpour not_allowed)
				(footprints allowed)
			)
			(placement
				(enabled no)
				(sheetname "")
			)
			(fill
				(thermal_gap 0.5)
				(thermal_bridge_width 0.5)
				(island_removal_mode 0)
			)
			(polygon
				(pts
					(xy 407.2001 -64.643) (xy 407.2001 -65.151) (xy 407.5811 -65.151) (xy 407.5811 -64.643)
				)
			)
		)
		(zone
			(layer "F.Cu")
			(hatch none 0.5)
			(connect_pads
				(clearance 0)
			)
			(min_thickness 0.25)
			(keepout
				(tracks not_allowed)
				(vias allowed)
				(pads allowed)
				(copperpour not_allowed)
				(footprints allowed)
			)
			(placement
				(enabled no)
				(sheetname "")
			)
			(fill
				(thermal_gap 0.5)
				(thermal_bridge_width 0.5)
				(island_removal_mode 0)
			)
			(polygon
				(pts
					(xy 407.5811 -64.643) (xy 407.5811 -65.151) (xy 407.2001 -65.151) (xy 407.2001 -64.643)
				)
			)
		)
	)
)
